# BASEBOARD_FAB2 (Tioga Pass) — schematic netlist excerpt (pin names and nets, part order shuffled) for the footprints in the layout excerpt that follows; sources: Cadence DE-HDL packaged netlist, KiCad conversion of Wiwynn_Tioga_Pass_MB.brd

C3B3  CAPP  330UF 6.3V 20% POSCAP  pkg 7343LF  page 234 : A = PVPP_KLM ; B = GND
C6F3  CAP_A  0.1UF 16V 10% X7R  pkg 0402V  page 99 : A = PVPP_ABC ; B = GND
R3P29  RES  64.9 1.0% CHIP  pkg 0402  page 96 : A = PVDDQ_DEF ; B = PWRGD_CPU0_DRAMPWROK_DEF_G

(kicad_pcb
	(version 20260206)
	(generator "pcbnew")
	(generator_version "10.0")
	(general
		(thickness 1.6)
		(legacy_teardrops no)
	)
	(paper "A4")
	(title_block
		(title "Wiwynn_Tioga_Pass_MB.brd")
		(comment 1 "Tioga Pass / footprints 176-178 of 4770")
	)
	(layers
		(0 "F.Cu" signal "TOP")
		(4 "In1.Cu" signal "L2GND")
		(6 "In2.Cu" signal "L3")
		(8 "In3.Cu" signal "L4GND")
		(10 "In4.Cu" signal "L5")
		(12 "In5.Cu" signal "L6GND")
		(14 "In6.Cu" signal "L7VCC")
		(16 "In7.Cu" signal "L8VCC")
		(18 "In8.Cu" signal "L9GND")
		(20 "In9.Cu" signal "L10")
		(22 "In10.Cu" signal "L11GND")
		(24 "In11.Cu" signal "L12")
		(26 "In12.Cu" signal "L13GND")
		(2 "B.Cu" signal "BOTTOM")
		(9 "F.Adhes" user "F.Adhesive")
		(11 "B.Adhes" user "B.Adhesive")
		(13 "F.Paste" user "Package Geometry/Pastemask Top")
		(15 "B.Paste" user "Package Geometry/Pastemask Bottom")
		(5 "F.SilkS" user "Ref Des/Silkscreen Top")
		(7 "B.SilkS" user "Ref Des/Silkscreen Bottom")
		(1 "F.Mask" user "Board Geometry/Soldermask Top")
		(3 "B.Mask" user "Board Geometry/Soldermask Bottom")
		(17 "Dwgs.User" user "User.Drawings")
		(19 "Cmts.User" user "User.Comments")
		(21 "Eco1.User" user "User.Eco1")
		(23 "Eco2.User" user "User.Eco2")
		(25 "Edge.Cuts" user "Board Geometry/Outline")
		(27 "Margin" user)
		(31 "F.CrtYd" user "Package Geometry/Place Bound Top")
		(29 "B.CrtYd" user "Package Geometry/Place Bound Bottom")
		(35 "F.Fab" user "Ref Des/Assembly Top")
		(33 "B.Fab" user "Ref Des/Assembly Bottom")
	)
	(footprint ""
		(layer "F.Cu")
		(at 325.0057 -29.25318)
		(property "Reference" "C6F3"
			(at 0 0 0)
			(layer "F.SilkS")
			(hide yes)
			(effects
				(font
					(size 1.27 1.27)
				)
			)
		)
		(property "Value" ""
			(at 0 0 0)
			(layer "F.Fab")
			(effects
				(font
					(size 1.27 1.27)
				)
			)
		)
		(duplicate_pad_numbers_are_jumpers no)
		(fp_poly
			(pts
				(xy 0.3048 -0.1016) (xy 0.3048 0.9906) (xy -0.3048 0.9906) (xy -0.3048 -0.1016)
			)
			(stroke
				(width 0)
				(type default)
			)
			(fill no)
			(layer "F.CrtYd")
		)
		(fp_line
			(start -0.3048 -0.1016)
			(end -0.3048 0.9906)
			(stroke
				(width 0.1)
				(type default)
			)
			(layer "F.Fab")
		)
		(fp_line
			(start -0.3048 0.9906)
			(end 0.3048 0.9906)
			(stroke
				(width 0.1)
				(type default)
			)
			(layer "F.Fab")
		)
		(fp_line
			(start 0.3048 -0.1016)
			(end -0.3048 -0.1016)
			(stroke
				(width 0.1)
				(type default)
			)
			(layer "F.Fab")
		)
		(fp_line
			(start 0.3048 0.9906)
			(end 0.3048 -0.1016)
			(stroke
				(width 0.1)
				(type default)
			)
			(layer "F.Fab")
		)
		(pad "1" smd rect
			(at 0 0)
			(size 0.508 0.508)
			(layers "F.Cu" "F.Mask" "F.Paste")
			(net "PVPP_ABC")
		)
		(pad "2" smd rect
			(at 0 0.889)
			(size 0.508 0.508)
			(layers "F.Cu" "F.Mask" "F.Paste")
			(net "GND")
		)
		(zone
			(layer "F.Cu")
			(hatch none 0.5)
			(connect_pads
				(clearance 0)
			)
			(min_thickness 0.25)
			(keepout
				(tracks allowed)
				(vias not_allowed)
				(pads allowed)
				(copperpour not_allowed)
				(footprints allowed)
			)
			(placement
				(enabled no)
				(sheetname "")
			)
			(fill
				(thermal_gap 0.5)
				(thermal_bridge_width 0.5)
				(island_removal_mode 0)
			)
			(polygon
				(pts
					(xy 324.7517 -28.99918) (xy 325.2597 -28.99918) (xy 325.2597 -28.61818) (xy 324.7517 -28.61818)
				)
			)
		)
		(zone
			(layer "F.Cu")
			(hatch none 0.5)
			(connect_pads
				(clearance 0)
			)
			(min_thickness 0.25)
			(keepout
				(tracks not_allowed)
				(vias allowed)
				(pads allowed)
				(copperpour not_allowed)
				(footprints allowed)
			)
			(placement
				(enabled no)
				(sheetname "")
			)
			(fill
				(thermal_gap 0.5)
				(thermal_bridge_width 0.5)
				(island_removal_mode 0)
			)
			(polygon
				(pts
					(xy 324.7517 -28.61818) (xy 325.2597 -28.61818) (xy 325.2597 -28.99918) (xy 324.7517 -28.99918)
				)
			)
		)
	)
	(footprint ""
		(layer "F.Cu")
		(at 153.6446 -126.7714 -90)
		(property "Reference" "C3B3"
			(at 3.10007 5.3086 0)
			(unlocked yes)
			(layer "F.SilkS")
			(effects
				(font
					(size 0.7874 0.5842)
					(thickness 0.1524)
				)
				(justify left)
			)
		)
		(property "Value" ""
			(at 0 0 270)
			(layer "F.Fab")
			(effects
				(font
					(size 1.27 1.27)
				)
			)
		)
		(duplicate_pad_numbers_are_jumpers no)
		(fp_line
			(start -2.2987 7.3533)
			(end -1.7272 7.3533)
			(stroke
				(width 0.1524)
				(type default)
			)
			(layer "F.SilkS")
		)
		(fp_line
			(start 1.7272 7.3533)
			(end 2.2987 7.3533)
			(stroke
				(width 0.1524)
				(type default)
			)
			(layer "F.SilkS")
		)
		(fp_line
			(start 2.2987 7.3533)
			(end 2.2987 -0.2413)
			(stroke
				(width 0.1524)
				(type default)
			)
			(layer "F.SilkS")
		)
		(fp_line
			(start -2.032 1.524)
			(end -1.7272 1.524)
			(stroke
				(width 0.1524)
				(type default)
			)
			(layer "F.SilkS")
		)
		(fp_line
			(start 2.032 1.524)
			(end 1.7272 1.524)
			(stroke
				(width 0.1524)
				(type default)
			)
			(layer "F.SilkS")
		)
		(fp_line
			(start -2.2987 -0.2413)
			(end -2.2987 7.3533)
			(stroke
				(width 0.1524)
				(type default)
			)
			(layer "F.SilkS")
		)
		(fp_line
			(start -2.032 -0.2413)
			(end -2.2987 -0.2413)
			(stroke
				(width 0.1524)
				(type default)
			)
			(layer "F.SilkS")
		)
		(fp_line
			(start 2.2987 -0.2413)
			(end 2.032 -0.2413)
			(stroke
				(width 0.1524)
				(type default)
			)
			(layer "F.SilkS")
		)
		(fp_line
			(start -2.032 -1.524)
			(end -2.032 1.524)
			(stroke
				(width 0.1524)
				(type default)
			)
			(layer "F.SilkS")
		)
		(fp_line
			(start -1.7272 -1.524)
			(end -2.032 -1.524)
			(stroke
				(width 0.1524)
				(type default)
			)
			(layer "F.SilkS")
		)
		(fp_line
			(start 1.7272 -1.524)
			(end 2.032 -1.524)
			(stroke
				(width 0.1524)
				(type default)
			)
			(layer "F.SilkS")
		)
		(fp_line
			(start 2.032 -1.524)
			(end 2.032 1.524)
			(stroke
				(width 0.1524)
				(type default)
			)
			(layer "F.SilkS")
		)
		(fp_poly
			(pts
				(xy -2.2987 -0.2413) (xy 2.2987 -0.2413) (xy 2.2987 7.3533) (xy -2.2987 7.3533)
			)
			(stroke
				(width 0)
				(type default)
			)
			(fill no)
			(layer "F.CrtYd")
		)
		(fp_line
			(start -2.2987 7.3533)
			(end -2.2987 -0.2413)
			(stroke
				(width 0.1)
				(type default)
			)
			(layer "F.Fab")
		)
		(fp_line
			(start 2.2987 7.3533)
			(end -2.2987 7.3533)
			(stroke
				(width 0.1)
				(type default)
			)
			(layer "F.Fab")
		)
		(fp_line
			(start -2.2987 -0.2413)
			(end 2.2987 -0.2413)
			(stroke
				(width 0.1)
				(type default)
			)
			(layer "F.Fab")
		)
		(fp_line
			(start 2.2987 -0.2413)
			(end 2.2987 7.3533)
			(stroke
				(width 0.1)
				(type default)
			)
			(layer "F.Fab")
		)
		(pad "1" smd rect
			(at 0 0 270)
			(size 2.54 3.048)
			(layers "F.Cu" "F.Mask" "F.Paste")
			(net "PVPP_KLM")
		)
		(pad "2" smd rect
			(at 0 7.112 270)
			(size 2.54 3.048)
			(layers "F.Cu" "F.Mask" "F.Paste")
			(net "GND")
		)
	)
	(footprint ""
		(layer "F.Cu")
		(at 273.37258 -84.39912 180)
		(property "Reference" "R3P29"
			(at 0 0 180)
			(layer "F.SilkS")
			(hide yes)
			(effects
				(font
					(size 1.27 1.27)
				)
			)
		)
		(property "Value" ""
			(at 0 0 180)
			(layer "F.Fab")
			(effects
				(font
					(size 1.27 1.27)
				)
			)
		)
		(duplicate_pad_numbers_are_jumpers no)
		(fp_poly
			(pts
				(xy -0.2794 -0.1016) (xy 0.2794 -0.1016) (xy 0.2794 0.9906) (xy -0.2794 0.9906)
			)
			(stroke
				(width 0)
				(type default)
			)
			(fill no)
			(layer "F.CrtYd")
		)
		(fp_line
			(start 0.2794 0.9906)
			(end 0.2794 -0.1016)
			(stroke
				(width 0.1)
				(type default)
			)
			(layer "F.Fab")
		)
		(fp_line
			(start 0.2794 -0.1016)
			(end -0.2794 -0.1016)
			(stroke
				(width 0.1)
				(type default)
			)
			(layer "F.Fab")
		)
		(fp_line
			(start -0.2794 0.9906)
			(end 0.2794 0.9906)
			(stroke
				(width 0.1)
				(type default)
			)
			(layer "F.Fab")
		)
		(fp_line
			(start -0.2794 -0.1016)
			(end -0.2794 0.9906)
			(stroke
				(width 0.1)
				(type default)
			)
			(layer "F.Fab")
		)
		(pad "1" smd rect
			(at 0 0 180)
			(size 0.508 0.508)
			(layers "F.Cu" "F.Mask" "F.Paste")
			(net "PVDDQ_DEF")
		)
		(pad "2" smd rect
			(at 0 0.889 180)
			(size 0.508 0.508)
			(layers "F.Cu" "F.Mask" "F.Paste")
			(net "PWRGD_CPU0_DRAMPWROK_DEF_G")
		)
		(zone
			(layer "F.Cu")
			(hatch none 0.5)
			(connect_pads
				(clearance 0)
			)
			(min_thickness 0.25)
			(keepout
				(tracks not_allowed)
				(vias allowed)
				(pads allowed)
				(copperpour not_allowed)
				(footprints allowed)
			)
			(placement
				(enabled no)
				(sheetname "")
			)
			(fill
				(thermal_gap 0.5)
				(thermal_bridge_width 0.5)
				(island_removal_mode 0)
			)
			(polygon
				(pts
					(xy 273.62658 -85.03412) (xy 273.11858 -85.03412) (xy 273.11858 -84.65312) (xy 273.62658 -84.65312)
				)
			)
		)
		(zone
			(layer "F.Cu")
			(hatch none 0.5)
			(connect_pads
				(clearance 0)
			)
			(min_thickness 0.25)
			(keepout
				(tracks allowed)
				(vias not_allowed)
				(pads allowed)
				(copperpour not_allowed)
				(footprints allowed)
			)
			(placement
				(enabled no)
				(sheetname "")
			)
			(fill
				(thermal_gap 0.5)
				(thermal_bridge_width 0.5)
				(island_removal_mode 0)
			)
			(polygon
				(pts
					(xy 273.62658 -84.65312) (xy 273.11858 -84.65312) (xy 273.11858 -85.03412) (xy 273.62658 -85.03412)
				)
			)
		)
	)
)
